# T6G (Grand Teton) — schematic netlist excerpt (pin names and nets, part order shuffled) for the footprints in the layout excerpt that follows; sources: Cadence DE-HDL packaged netlist, KiCad conversion of 04192023_DAF0TMB3IC0_F0TG_MB_C_brd_V02_OCP.brd

C473  Q_CAP  0.1UF 10V 10% X7S  pkg C0201  page 356 : A = P0V9_CPU1_RT3_2A ; B = GND

U192  LTC4307CMS8  IC  pkg MSOP8  page 240
  ENABLE  = MB_PDB_SMB9_R_EN
  SCL_OUT  = SMB_FAN_3V3AUX_BUF_SCL
  SCL_IN  = SMB_FAN_3V3AUX_R_SCL
  GND  = GND
  READY  = NC
  SDA_IN  = SMB_FAN_3V3AUX_R_SDA
  SDA_OUT  = SMB_FAN_3V3AUX_BUF_SDA
  VCC  = P3V3_AUX

(kicad_pcb
	(version 20260206)
	(generator "pcbnew")
	(generator_version "10.0")
	(general
		(thickness 1.6)
		(legacy_teardrops no)
	)
	(paper "A4")
	(title_block
		(title "04192023_DAF0TMB3IC0_F0TG_MB_C_brd_V02_OCP.brd")
		(comment 1 "Grand Teton / footprints 6947-6948 of 8354")
	)
	(layers
		(0 "F.Cu" signal "TOP")
		(4 "In1.Cu" signal "GND")
		(6 "In2.Cu" signal "IN1")
		(8 "In3.Cu" signal "GND1")
		(10 "In4.Cu" signal "IN2")
		(12 "In5.Cu" signal "GND2")
		(14 "In6.Cu" signal "IN3")
		(16 "In7.Cu" signal "GND3")
		(18 "In8.Cu" signal "VCC")
		(20 "In9.Cu" signal "VCC1")
		(22 "In10.Cu" signal "GND4")
		(24 "In11.Cu" signal "IN4")
		(26 "In12.Cu" signal "GND5")
		(28 "In13.Cu" signal "IN5")
		(30 "In14.Cu" signal "GND6")
		(32 "In15.Cu" signal "IN6")
		(34 "In16.Cu" signal "GND7")
		(2 "B.Cu" signal "BOTTOM")
		(9 "F.Adhes" user "F.Adhesive")
		(11 "B.Adhes" user "B.Adhesive")
		(13 "F.Paste" user "Package Geometry/Pastemask Top")
		(15 "B.Paste" user "Package Geometry/Pastemask Bottom")
		(5 "F.SilkS" user "Ref Des/Silkscreen Top")
		(7 "B.SilkS" user "Ref Des/Silkscreen Bottom")
		(1 "F.Mask" user "Board Geometry/Soldermask Top")
		(3 "B.Mask" user "Board Geometry/Soldermask Bottom")
		(17 "Dwgs.User" user "User.Drawings")
		(19 "Cmts.User" user "User.Comments")
		(21 "Eco1.User" user "User.Eco1")
		(23 "Eco2.User" user "User.Eco2")
		(25 "Edge.Cuts" user "Board Geometry/Outline")
		(27 "Margin" user)
		(31 "F.CrtYd" user "Package Geometry/Place Bound Top")
		(29 "B.CrtYd" user "Package Geometry/Place Bound Bottom")
		(35 "F.Fab" user "Ref Des/Assembly Top")
		(33 "B.Fab" user "Ref Des/Assembly Bottom")
	)
	(footprint ""
		(layer "B.Cu")
		(at 178.303428 -418.4015)
		(property "Reference" "U192"
			(at -0.814578 2.297176 0)
			(unlocked yes)
			(layer "B.SilkS")
			(effects
				(font
					(size 0.7874 0.5842)
					(thickness 0.1524)
				)
				(justify left mirror)
			)
		)
		(property "Value" ""
			(at 0 0 0)
			(layer "B.Fab")
			(effects
				(font
					(size 1.27 1.27)
				)
				(justify mirror)
			)
		)
		(duplicate_pad_numbers_are_jumpers no)
		(fp_line
			(start -1.3716 -1.524)
			(end -1.3716 1.524)
			(stroke
				(width 0.1524)
				(type default)
			)
			(layer "B.SilkS")
		)
		(fp_line
			(start -1.3716 1.524)
			(end 1.3716 1.524)
			(stroke
				(width 0.1524)
				(type default)
			)
			(layer "B.SilkS")
		)
		(fp_line
			(start -0.508 -1.524)
			(end -1.3716 -1.524)
			(stroke
				(width 0.1524)
				(type default)
			)
			(layer "B.SilkS")
		)
		(fp_line
			(start 0 -1.016)
			(end -0.508 -1.524)
			(stroke
				(width 0.1524)
				(type default)
			)
			(layer "B.SilkS")
		)
		(fp_line
			(start 0.508 -1.524)
			(end 0 -1.016)
			(stroke
				(width 0.1524)
				(type default)
			)
			(layer "B.SilkS")
		)
		(fp_line
			(start 1.3716 -1.524)
			(end 0.508 -1.524)
			(stroke
				(width 0.1524)
				(type default)
			)
			(layer "B.SilkS")
		)
		(fp_line
			(start 1.3716 1.524)
			(end 1.3716 -1.524)
			(stroke
				(width 0.1524)
				(type default)
			)
			(layer "B.SilkS")
		)
		(fp_poly
			(pts
				(xy 3.631946 -1.31826) (xy 3.19024 -1.76022) (xy 3.030728 -1.13665)
			)
			(stroke
				(width 0)
				(type default)
			)
			(fill yes)
			(layer "B.SilkS")
		)
		(fp_line
			(start -2.54 -1.0668)
			(end -2.54 1.0668)
			(stroke
				(width 0.1)
				(type default)
			)
			(layer "B.Fab")
		)
		(fp_line
			(start -2.54 1.0668)
			(end -1.5494 1.0668)
			(stroke
				(width 0.1)
				(type default)
			)
			(layer "B.Fab")
		)
		(fp_line
			(start -1.5494 -1.524)
			(end -1.5494 -1.0668)
			(stroke
				(width 0.1)
				(type default)
			)
			(layer "B.Fab")
		)
		(fp_line
			(start -1.5494 -1.0668)
			(end -2.54 -1.0668)
			(stroke
				(width 0.1)
				(type default)
			)
			(layer "B.Fab")
		)
		(fp_line
			(start -1.5494 -1.0668)
			(end -1.5494 1.0668)
			(stroke
				(width 0.1)
				(type default)
			)
			(layer "B.Fab")
		)
		(fp_line
			(start -1.5494 1.0668)
			(end -1.5494 1.524)
			(stroke
				(width 0.1)
				(type default)
			)
			(layer "B.Fab")
		)
		(fp_line
			(start -1.5494 1.524)
			(end 1.5494 1.524)
			(stroke
				(width 0.1)
				(type default)
			)
			(layer "B.Fab")
		)
		(fp_line
			(start 1.5494 -1.524)
			(end -1.5494 -1.524)
			(stroke
				(width 0.1)
				(type default)
			)
			(layer "B.Fab")
		)
		(fp_line
			(start 1.5494 -1.0668)
			(end 1.5494 -1.524)
			(stroke
				(width 0.1)
				(type default)
			)
			(layer "B.Fab")
		)
		(fp_line
			(start 1.5494 1.0668)
			(end 1.5494 -1.0668)
			(stroke
				(width 0.1)
				(type default)
			)
			(layer "B.Fab")
		)
		(fp_line
			(start 1.5494 1.0668)
			(end 2.54 1.0668)
			(stroke
				(width 0.1)
				(type default)
			)
			(layer "B.Fab")
		)
		(fp_line
			(start 1.5494 1.524)
			(end 1.5494 1.0668)
			(stroke
				(width 0.1)
				(type default)
			)
			(layer "B.Fab")
		)
		(fp_line
			(start 2.54 -1.0668)
			(end 1.5494 -1.0668)
			(stroke
				(width 0.1)
				(type default)
			)
			(layer "B.Fab")
		)
		(fp_line
			(start 2.54 1.0668)
			(end 2.54 -1.0668)
			(stroke
				(width 0.1)
				(type default)
			)
			(layer "B.Fab")
		)
		(fp_poly
			(pts
				(xy 3.60172 -0.719328) (xy 3.60172 -1.344168) (xy 3.048 -1.016)
			)
			(stroke
				(width 0)
				(type default)
			)
			(fill yes)
			(layer "B.Fab")
		)
		(pad "1" smd rect
			(at 2.232406 -0.975106 270)
			(size 0.3556 1.4224)
			(layers "B.Cu" "B.Mask" "B.Paste")
			(net "MB_PDB_SMB9_R_EN")
		)
		(pad "2" smd rect
			(at 2.232406 -0.32512 270)
			(size 0.3556 1.4224)
			(layers "B.Cu" "B.Mask" "B.Paste")
			(net "SMB_FAN_3V3AUX_BUF_SCL")
		)
		(pad "3" smd rect
			(at 2.232406 0.32512 270)
			(size 0.3556 1.4224)
			(layers "B.Cu" "B.Mask" "B.Paste")
			(net "SMB_FAN_3V3AUX_R_SCL")
		)
		(pad "4" smd rect
			(at 2.232406 0.975106 270)
			(size 0.3556 1.4224)
			(layers "B.Cu" "B.Mask" "B.Paste")
			(net "GND")
		)
		(pad "5" smd rect
			(at -2.232406 0.975106 270)
			(size 0.3556 1.4224)
			(layers "B.Cu" "B.Mask" "B.Paste")
			(net "Net_10751")
		)
		(pad "6" smd rect
			(at -2.232406 0.32512 270)
			(size 0.3556 1.4224)
			(layers "B.Cu" "B.Mask" "B.Paste")
			(net "SMB_FAN_3V3AUX_R_SDA")
		)
		(pad "7" smd rect
			(at -2.232406 -0.32512 270)
			(size 0.3556 1.4224)
			(layers "B.Cu" "B.Mask" "B.Paste")
			(net "SMB_FAN_3V3AUX_BUF_SDA")
		)
		(pad "8" smd rect
			(at -2.232406 -0.975106 270)
			(size 0.3556 1.4224)
			(layers "B.Cu" "B.Mask" "B.Paste")
			(net "P3V3_AUX")
		)
	)
	(footprint ""
		(layer "B.Cu")
		(at 129.018538 -388.011162 -90)
		(property "Reference" "C473"
			(at 0 0 90)
			(layer "B.SilkS")
			(hide yes)
			(effects
				(font
					(size 1.27 1.27)
				)
				(justify mirror)
			)
		)
		(property "Value" ""
			(at 0 0 90)
			(layer "B.Fab")
			(effects
				(font
					(size 1.27 1.27)
				)
				(justify mirror)
			)
		)
		(duplicate_pad_numbers_are_jumpers no)
		(fp_line
			(start -0.299974 0.150114)
			(end 0.299974 0.150114)
			(stroke
				(width 0.1)
				(type default)
			)
			(layer "B.Fab")
		)
		(fp_line
			(start 0.299974 0.150114)
			(end 0.299974 -0.150114)
			(stroke
				(width 0.1)
				(type default)
			)
			(layer "B.Fab")
		)
		(fp_line
			(start -0.299974 -0.150114)
			(end -0.299974 0.150114)
			(stroke
				(width 0.1)
				(type default)
			)
			(layer "B.Fab")
		)
		(fp_line
			(start 0.299974 -0.150114)
			(end -0.299974 -0.150114)
			(stroke
				(width 0.1)
				(type default)
			)
			(layer "B.Fab")
		)
		(pad "1" smd rect
			(at 0.2667 0 90)
			(size 0.3048 0.381)
			(layers "B.Cu" "B.Mask" "B.Paste")
			(net "P0V9_CPU1_RT3_2A")
		)
		(pad "2" smd rect
			(at -0.2667 0 90)
			(size 0.3048 0.381)
			(layers "B.Cu" "B.Mask" "B.Paste")
			(net "GND")
		)
	)
)
